(kicad_pcb
	(version 20221018)
	(generator pcbnew)
	(general
    (thickness 1.62)
  )
	(paper "A4")
	(title_block
    (title "ECP5 - Datacenter Secure Control Module (DC-SCM)")
    (date "2024-07-01")
    (rev "1.2.1")
		(comment 9 "footprints 37-41 of 506")
	)
	(layers
    (0 "F.Cu" signal)
    (1 "In1.Cu" power)
    (2 "In2.Cu" signal)
    (3 "In3.Cu" power)
    (4 "In4.Cu" power)
    (5 "In5.Cu" signal)
    (6 "In6.Cu" power)
    (31 "B.Cu" signal)
    (32 "B.Adhes" user "B.Adhesive")
    (33 "F.Adhes" user "F.Adhesive")
    (34 "B.Paste" user)
    (35 "F.Paste" user)
    (36 "B.SilkS" user "B.Silkscreen")
    (37 "F.SilkS" user "F.Silkscreen")
    (38 "B.Mask" user)
    (39 "F.Mask" user)
    (40 "Dwgs.User" user "User.Drawings")
    (41 "Cmts.User" user "User.Comments")
    (42 "Eco1.User" user "User.Eco1")
    (43 "Eco2.User" user "User.Eco2")
    (44 "Edge.Cuts" user)
    (45 "Margin" user)
    (46 "B.CrtYd" user "B.Courtyard")
    (47 "F.CrtYd" user "F.Courtyard")
    (48 "B.Fab" user)
    (49 "F.Fab" user)
  )
	(footprint "antmicro-footprints:VQFN-20_1EP_4.5x2.5mm_P0.5mm" (layer "F.Cu")
    (at 90.9 145.35 -90)
    (property "Author" "Antmicro")
    (property "License" "Apache-2.0")
    (property "MPN" "NVT2008BQ,115")
    (property "Manufacturer" "NXP")
    (property "Sheetfile" "interfaces.kicad_sch")
    (property "Sheetname" "Interfaces")
    (property "ki_description" "Bidirectional Voltage Level Translator, 8 Inputs, 1.5ns, 1.8V to 5.5V, DHVQFN-20")
    (property "ki_keywords" "SMT, LEVEL-SHIFTER, IC, LOGIC")
    (attr smd)
    (fp_text reference "U7" (at 2.03 2.59 90) (layer "F.SilkS")
        (effects (font (size 0.7 0.7) (thickness 0.127)))
    )
    (fp_text value "NVT2008BQ,115" (at 0.69 2.96 90) (layer "F.Fab") hide
        (effects (font (size 1 1) (thickness 0.015)))
    )
    (fp_text user "${REFERENCE}" (at -3.347 4.959 -90) (layer "F.Fab") hide
        (effects (font (size 0.7 0.7) (thickness 0.15)) (justify left bottom))
    )
    (fp_text user "Author: Antmicro" (at -3.347 6.16 -90) (layer "F.Fab") hide
        (effects (font (size 0.7 0.7) (thickness 0.15)) (justify left bottom))
    )
    (fp_text user "License: Apache-2.0" (at -3.347 7.36 -90) (layer "F.Fab") hide
        (effects (font (size 0.7 0.7) (thickness 0.15)) (justify left bottom))
    )
    (fp_poly
      (pts
        (xy -0.951 -0.32)
        (xy 0.949 -0.32)
        (xy 0.949 0.32)
        (xy -0.951 0.32)
      )

      (stroke (width 0.01) (type solid)) (fill solid) (layer "F.Paste"))
    (fp_line (start -2.25 -1.25) (end -2.25 -0.5)
      (stroke (width 0.15) (type solid)) (layer "F.SilkS"))
    (fp_line (start -2.249 1.25) (end -2 1.25)
      (stroke (width 0.15) (type solid)) (layer "F.SilkS"))
    (fp_line (start -2.001 -1.25) (end -2.25 -1.25)
      (stroke (width 0.15) (type solid)) (layer "F.SilkS"))
    (fp_line (start 2.249 -1.25) (end 2 -1.25)
      (stroke (width 0.15) (type solid)) (layer "F.SilkS"))
    (fp_line (start 2.249 -1.25) (end 2.249 -0.5)
      (stroke (width 0.15) (type solid)) (layer "F.SilkS"))
    (fp_line (start 2.249 1.249) (end 2 1.249)
      (stroke (width 0.15) (type solid)) (layer "F.SilkS"))
    (fp_line (start 2.249 1.249) (end 2.249 0.5)
      (stroke (width 0.15) (type solid)) (layer "F.SilkS"))
    (fp_rect (start -2.711 -1.71) (end 2.708 1.709)
      (stroke (width 0.05) (type solid)) (fill none) (layer "F.CrtYd"))
    (fp_line (start -2.25 1.249) (end -2.25 -1.25)
      (stroke (width 0.15) (type solid)) (layer "F.Fab"))
    (fp_line (start 2.249 -1.25) (end -2.25 -1.25)
      (stroke (width 0.15) (type solid)) (layer "F.Fab"))
    (fp_line (start 2.249 1.249) (end -2.25 1.249)
      (stroke (width 0.15) (type solid)) (layer "F.Fab"))
    (fp_line (start 2.249 1.249) (end 2.249 -1.25)
      (stroke (width 0.15) (type solid)) (layer "F.Fab"))
    (pad "1" smd roundrect (at -2.186 0.248) (size 0.26 0.86) (layers "F.Cu" "F.Paste" "F.Mask") (roundrect_rratio 0.25)
      (chamfer_ratio 0.3) (chamfer top_left)
      (net 1 "GND") (pinfunction "GND") (pintype "power_in"))
    (pad "2" smd roundrect (at -1.75 1.185 270) (size 0.26 0.86) (layers "F.Cu" "F.Paste" "F.Mask") (roundrect_rratio 0.2)
      (net 12 "VCC1V0") (pinfunction "VREFA") (pintype "power_in"))
    (pad "3" smd roundrect (at -1.25 1.185 270) (size 0.26 0.86) (layers "F.Cu" "F.Paste" "F.Mask") (roundrect_rratio 0.2)
      (net 206 "I3C[0]_SCL_1V0") (pinfunction "A1") (pintype "bidirectional"))
    (pad "4" smd roundrect (at -0.75 1.185 270) (size 0.26 0.86) (layers "F.Cu" "F.Paste" "F.Mask") (roundrect_rratio 0.2)
      (net 205 "I3C[0]_SDA_1V0") (pinfunction "A2") (pintype "bidirectional"))
    (pad "5" smd roundrect (at -0.25 1.185 270) (size 0.26 0.86) (layers "F.Cu" "F.Paste" "F.Mask") (roundrect_rratio 0.2)
      (net 208 "I3C[1]_SCL_1V0") (pinfunction "A3") (pintype "bidirectional"))
    (pad "6" smd roundrect (at 0.248 1.185 270) (size 0.26 0.86) (layers "F.Cu" "F.Paste" "F.Mask") (roundrect_rratio 0.2)
      (net 207 "I3C[1]_SDA_1V0") (pinfunction "A4") (pintype "bidirectional"))
    (pad "7" smd roundrect (at 0.748 1.185 270) (size 0.26 0.86) (layers "F.Cu" "F.Paste" "F.Mask") (roundrect_rratio 0.2)
      (net 210 "I3C[2]_SCL_1V0") (pinfunction "A5") (pintype "bidirectional"))
    (pad "8" smd roundrect (at 1.249 1.185 270) (size 0.26 0.86) (layers "F.Cu" "F.Paste" "F.Mask") (roundrect_rratio 0.2)
      (net 209 "I3C[2]_SDA_1V0") (pinfunction "A6") (pintype "bidirectional"))
    (pad "9" smd roundrect (at 1.749 1.185 270) (size 0.26 0.86) (layers "F.Cu" "F.Paste" "F.Mask") (roundrect_rratio 0.2)
      (net 204 "I3C[3]_SCL_1V0") (pinfunction "A7") (pintype "bidirectional"))
    (pad "10" smd roundrect (at 2.185 0.248) (size 0.26 0.86) (layers "F.Cu" "F.Paste" "F.Mask") (roundrect_rratio 0.2)
      (net 203 "I3C[3]_SDA_1V0") (pinfunction "A8") (pintype "bidirectional"))
    (pad "11" smd roundrect (at 2.185 -0.25) (size 0.26 0.86) (layers "F.Cu" "F.Paste" "F.Mask") (roundrect_rratio 0.2)
      (net 173 "I3C[3]_SDA_3V3") (pinfunction "B8") (pintype "bidirectional"))
    (pad "12" smd roundrect (at 1.749 -1.186 270) (size 0.26 0.86) (layers "F.Cu" "F.Paste" "F.Mask") (roundrect_rratio 0.2)
      (net 174 "I3C[3]_SCL_3V3") (pinfunction "B7") (pintype "bidirectional"))
    (pad "13" smd roundrect (at 1.249 -1.186 270) (size 0.26 0.86) (layers "F.Cu" "F.Paste" "F.Mask") (roundrect_rratio 0.2)
      (net 171 "I3C[2]_SDA_3V3") (pinfunction "B6") (pintype "bidirectional"))
    (pad "14" smd roundrect (at 0.748 -1.186 270) (size 0.26 0.86) (layers "F.Cu" "F.Paste" "F.Mask") (roundrect_rratio 0.2)
      (net 172 "I3C[2]_SCL_3V3") (pinfunction "B5") (pintype "bidirectional"))
    (pad "15" smd roundrect (at 0.248 -1.186 270) (size 0.26 0.86) (layers "F.Cu" "F.Paste" "F.Mask") (roundrect_rratio 0.2)
      (net 169 "I3C[1]_SDA_3V3") (pinfunction "B4") (pintype "bidirectional"))
    (pad "16" smd roundrect (at -0.25 -1.186 270) (size 0.26 0.86) (layers "F.Cu" "F.Paste" "F.Mask") (roundrect_rratio 0.2)
      (net 170 "I3C[1]_SCL_3V3") (pinfunction "B3") (pintype "bidirectional"))
    (pad "17" smd roundrect (at -0.75 -1.186 270) (size 0.26 0.86) (layers "F.Cu" "F.Paste" "F.Mask") (roundrect_rratio 0.2)
      (net 167 "I3C[0]_SDA_3V3") (pinfunction "B2") (pintype "bidirectional"))
    (pad "18" smd roundrect (at -1.25 -1.186 270) (size 0.26 0.86) (layers "F.Cu" "F.Paste" "F.Mask") (roundrect_rratio 0.2)
      (net 168 "I3C[0]_SCL_3V3") (pinfunction "B1") (pintype "bidirectional"))
    (pad "19" smd roundrect (at -1.75 -1.186 270) (size 0.26 0.86) (layers "F.Cu" "F.Paste" "F.Mask") (roundrect_rratio 0.2)
      (net 220 "Net-(U7-EN)") (pinfunction "VREFB") (pintype "power_in"))
    (pad "20" smd roundrect (at -2.186 -0.25) (size 0.26 0.86) (layers "F.Cu" "F.Paste" "F.Mask") (roundrect_rratio 0.2)
      (net 220 "Net-(U7-EN)") (pinfunction "EN") (pintype "input"))
    (pad "21" smd roundrect (at 0 0 270) (size 3 1) (layers "F.Cu" "F.Mask") (roundrect_rratio 0.1)
      (net 776 "unconnected-(U7-EP-Pad21)") (pinfunction "EP") (pintype "power_in+no_connect"))
  )
	(footprint "antmicro-footprints:C_0402_1005Metric" (layer "F.Cu")
    (at 87.4 141.05 -90)
    (descr "Capacitor SMD 0402")
    (tags "capacitor SMD 0402")
    (property "Author" "Antmicro")
    (property "Dielectric" "X5R")
    (property "License" "Apache-2.0")
    (property "MPN" "GRM155R61H104KE14D")
    (property "Manufacturer" "Murata")
    (property "Public" "False")
    (property "Sheetfile" "interfaces.kicad_sch")
    (property "Sheetname" "Interfaces")
    (property "Val" "100n")
    (property "Voltage" "50V")
    (property "ki_description" "SMD Multilayer Ceramic Capacitor, 0.1 µF, 50 V, 0402 [1005 Metric], ± 10%, X5R, GRM Series")
    (property "ki_keywords" "0402, SMT, CAPACITOR, PASSIVE, CERAMIC, MLCC")
    (attr smd)
    (fp_text reference "C55" (at -2.53 -0.03 90) (layer "F.SilkS")
        (effects (font (size 0.7 0.7) (thickness 0.127)))
    )
    (fp_text value "C_100n_0402" (at 0 1.17 90) (layer "F.Fab")
        (effects (font (size 1 1) (thickness 0.15)))
    )
    (fp_text user "License: Apache-2.0" (at -0.939 5.799 -90) (layer "F.Fab") hide
        (effects (font (size 0.7 0.7) (thickness 0.15)) (justify left bottom))
    )
    (fp_text user "${REFERENCE}" (at 0 0 90) (layer "F.Fab")
        (effects (font (size 0.25 0.25) (thickness 0.04)))
    )
    (fp_text user "Author: Antmicro" (at -0.939 3.399 -90) (layer "F.Fab") hide
        (effects (font (size 0.7 0.7) (thickness 0.15)) (justify left bottom))
    )
    (fp_rect (start -0.925 -0.47) (end 0.925 0.47)
      (stroke (width 0.05) (type default)) (fill none) (layer "F.CrtYd"))
    (fp_line (start -0.494 -0.25) (end 0.504 -0.25)
      (stroke (width 0.15) (type solid)) (layer "F.Fab"))
    (fp_line (start -0.494 0.248) (end -0.494 -0.25)
      (stroke (width 0.15) (type solid)) (layer "F.Fab"))
    (fp_line (start 0.504 -0.25) (end 0.504 0.248)
      (stroke (width 0.15) (type solid)) (layer "F.Fab"))
    (fp_line (start 0.504 0.248) (end -0.494 0.248)
      (stroke (width 0.15) (type solid)) (layer "F.Fab"))
    (pad "1" smd roundrect (at -0.48 0 270) (size 0.59 0.64) (layers "F.Cu" "F.Paste" "F.Mask") (roundrect_rratio 0.25)
      (net 1 "GND") (pintype "passive"))
    (pad "2" smd roundrect (at 0.48 0 270) (size 0.59 0.64) (layers "F.Cu" "F.Paste" "F.Mask") (roundrect_rratio 0.25)
      (net 220 "Net-(U7-EN)") (pintype "passive"))
  )
	(footprint "antmicro-footprints:R_0402_1005Metric" (layer "F.Cu")
    (at 86.25 141.05 -90)
    (descr "Resistor SMD 0402")
    (tags "resistor SMD 0402")
    (property "Author" "Antmicro")
    (property "License" "Apache-2.0")
    (property "MPN" "CR0402-FX-2003GLF")
    (property "Manufacturer" "Bourns")
    (property "Public" "False")
    (property "Sheetfile" "interfaces.kicad_sch")
    (property "Sheetname" "Interfaces")
    (property "Tolerance" "1%")
    (property "Val" "200k")
    (property "ki_description" "SMD Chip Resistor, 200 kohm, ± 1%, 62.5 mW, 0402 [1005 Metric], Thick Film, General Purpose")
    (property "ki_keywords" "0402, SMT, RESISTOR, PASSIVE")
    (attr smd)
    (fp_text reference "R57" (at -2.55 0.04 -90) (layer "F.SilkS")
        (effects (font (size 0.7 0.7) (thickness 0.127)))
    )
    (fp_text value "R_200k_0402" (at 0 1.17 -90) (layer "F.Fab")
        (effects (font (size 1 1) (thickness 0.15)))
    )
    (fp_text user "${REFERENCE}" (at 0 0 -90) (layer "F.Fab")
        (effects (font (size 0.25 0.25) (thickness 0.04)))
    )
    (fp_text user "License: Apache-2.0" (at -0.95 5.169 -90) (layer "F.Fab") hide
        (effects (font (size 0.7 0.7) (thickness 0.15)) (justify left bottom))
    )
    (fp_text user "Author: Antmicro" (at -0.95 4.169 -90) (layer "F.Fab") hide
        (effects (font (size 0.7 0.7) (thickness 0.15)) (justify left bottom))
    )
    (fp_rect (start -0.925 -0.47) (end 0.925 0.47)
      (stroke (width 0.05) (type default)) (fill none) (layer "F.CrtYd"))
    (fp_rect (start -0.5 -0.25) (end 0.5 0.25)
      (stroke (width 0.15) (type solid)) (fill none) (layer "F.Fab"))
    (pad "1" smd roundrect (at -0.48 0 270) (size 0.59 0.64) (layers "F.Cu" "F.Paste" "F.Mask") (roundrect_rratio 0.25)
      (net 385 "1V0_PG") (pintype "passive"))
    (pad "2" smd roundrect (at 0.48 0 270) (size 0.59 0.64) (layers "F.Cu" "F.Paste" "F.Mask") (roundrect_rratio 0.25)
      (net 220 "Net-(U7-EN)") (pintype "passive"))
  )
	(footprint "antmicro-footprints:C_0402_1005Metric" (layer "F.Cu")
    (at 71.42 122.04 -90)
    (descr "Capacitor SMD 0402")
    (tags "capacitor SMD 0402")
    (property "Author" "Antmicro")
    (property "Dielectric" "C0G")
    (property "License" "Apache-2.0")
    (property "MPN" "GRM1555C1H102JA01D")
    (property "Manufacturer" "Murata")
    (property "Public" "False")
    (property "Sheetfile" "ddr3.kicad_sch")
    (property "Sheetname" "DDR3")
    (property "Val" "1n")
    (property "Voltage" "50V")
    (property "ki_description" "SMD Multilayer Ceramic Capacitor, 1000 pF, 50 V, 0402 [1005 Metric], ± 5%, C0G / NP0, GRM Series")
    (property "ki_keywords" "0402, SMT, CAPACITOR, PASSIVE, CERAMIC, MLCC")
    (attr smd)
    (fp_text reference "C196" (at -0.055 1.99 90) (layer "F.SilkS")
        (effects (font (size 0.7 0.7) (thickness 0.127)))
    )
    (fp_text value "C_1n_0402" (at 0 1.17 90) (layer "F.Fab")
        (effects (font (size 1 1) (thickness 0.15)))
    )
    (fp_text user "${REFERENCE}" (at 0 0 90) (layer "F.Fab")
        (effects (font (size 0.25 0.25) (thickness 0.04)))
    )
    (fp_text user "License: Apache-2.0" (at -0.939 5.799 -90) (layer "F.Fab") hide
        (effects (font (size 0.7 0.7) (thickness 0.15)) (justify left bottom))
    )
    (fp_text user "Author: Antmicro" (at -0.939 3.399 -90) (layer "F.Fab") hide
        (effects (font (size 0.7 0.7) (thickness 0.15)) (justify left bottom))
    )
    (fp_rect (start -0.925 -0.47) (end 0.925 0.47)
      (stroke (width 0.05) (type default)) (fill none) (layer "F.CrtYd"))
    (fp_line (start -0.494 -0.25) (end 0.504 -0.25)
      (stroke (width 0.15) (type solid)) (layer "F.Fab"))
    (fp_line (start -0.494 0.248) (end -0.494 -0.25)
      (stroke (width 0.15) (type solid)) (layer "F.Fab"))
    (fp_line (start 0.504 -0.25) (end 0.504 0.248)
      (stroke (width 0.15) (type solid)) (layer "F.Fab"))
    (fp_line (start 0.504 0.248) (end -0.494 0.248)
      (stroke (width 0.15) (type solid)) (layer "F.Fab"))
    (pad "1" smd roundrect (at -0.48 0 270) (size 0.59 0.64) (layers "F.Cu" "F.Paste" "F.Mask") (roundrect_rratio 0.25)
      (net 1 "GND") (pintype "passive"))
    (pad "2" smd roundrect (at 0.48 0 270) (size 0.59 0.64) (layers "F.Cu" "F.Paste" "F.Mask") (roundrect_rratio 0.25)
      (net 305 "Net-(U11-REFIN)") (pintype "passive"))
  )
	(footprint "antmicro-footprints:LED_0603_1608Metric_G" (layer "F.Cu")
    (at 139.161 61.478 90)
    (descr "LED SMD 0603 Green")
    (tags "LED SMD 0603 Green")
    (property "Author" "Antmicro")
    (property "Color" "Green")
    (property "License" "Apache-2.0")
    (property "MPN" "LG L29K-G2J1-24-Z")
    (property "Manufacturer" "OSRAM")
    (property "Sheetfile" "interfaces.kicad_sch")
    (property "Sheetname" "Interfaces")
    (property "ki_description" "LED, Green, SMD, 0603, 20 mA, 1.7 V, 570 nm")
    (property "ki_keywords" "SMT, DIODE, SEMICONDUCTOR, LED")
    (attr smd)
    (fp_text reference "D3" (at 1.858 0.009) (layer "F.SilkS")
        (effects (font (size 0.7 0.7) (thickness 0.127)))
    )
    (fp_text value "LED_G_0603_LG_L29K-G2J1-24-Z" (at 0 1.77 90) (layer "F.Fab")
        (effects (font (size 1 1) (thickness 0.15)))
    )
    (fp_text user "${REFERENCE}" (at -1.4224 5.999 90) (layer "F.Fab") hide
        (effects (font (size 0.7 0.7) (thickness 0.15)) (justify left bottom))
    )
    (fp_text user "License: Apache-2.0" (at -1.4224 3.599 90) (layer "F.Fab") hide
        (effects (font (size 0.7 0.7) (thickness 0.15)) (justify left bottom))
    )
    (fp_text user "Author: Antmicro" (at -1.4224 4.799 90) (layer "F.Fab") hide
        (effects (font (size 0.7 0.7) (thickness 0.15)) (justify left bottom))
    )
    (fp_line (start -1.18 -0.319) (end -1.18 0.321)
      (stroke (width 0.15) (type solid)) (layer "F.SilkS"))
    (fp_line (start -0.094672 0.001008) (end -0.24 0.001008)
      (stroke (width 0.1) (type solid)) (layer "F.SilkS"))
    (fp_line (start -0.094672 0.001008) (end 0.105328 -0.198992)
      (stroke (width 0.1) (type solid)) (layer "F.SilkS"))
    (fp_line (start -0.094672 0.201008) (end -0.094672 -0.198992)
      (stroke (width 0.1) (type solid)) (layer "F.SilkS"))
    (fp_line (start 0.105328 0.001008) (end 0.24 0.001)
      (stroke (width 0.1) (type solid)) (layer "F.SilkS"))
    (fp_line (start 0.105328 0.201008) (end -0.094672 0.001008)
      (stroke (width 0.1) (type solid)) (layer "F.SilkS"))
    (fp_line (start 0.105328 0.201008) (end 0.105328 -0.198992)
      (stroke (width 0.1) (type solid)) (layer "F.SilkS"))
    (fp_line (start 0.22 -0.35) (end -0.22 -0.35)
      (stroke (width 0.15) (type solid)) (layer "F.SilkS"))
    (fp_line (start 0.22 0.35) (end -0.22 0.35)
      (stroke (width 0.15) (type solid)) (layer "F.SilkS"))
    (fp_rect (start 1.25 0.65) (end -1.25 -0.65)
      (stroke (width 0.05) (type solid)) (fill none) (layer "F.CrtYd"))
    (fp_line (start -0.199 -0.202) (end -0.199 0.1)
      (stroke (width 0.15) (type solid)) (layer "F.Fab"))
    (fp_line (start -0.199 0) (end -0.597 0)
      (stroke (width 0.15) (type solid)) (layer "F.Fab"))
    (fp_line (start -0.199 0.2) (end -0.199 0.1)
      (stroke (width 0.15) (type solid)) (layer "F.Fab"))
    (fp_line (start -0.101 0) (end 0.201 0.2)
      (stroke (width 0.15) (type solid)) (layer "F.Fab"))
    (fp_line (start 0.201 -0.202) (end -0.101 0)
      (stroke (width 0.15) (type solid)) (layer "F.Fab"))
    (fp_line (start 0.201 0) (end 0.201 -0.202)
      (stroke (width 0.15) (type solid)) (layer "F.Fab"))
    (fp_line (start 0.201 0.2) (end 0.201 0)
      (stroke (width 0.15) (type solid)) (layer "F.Fab"))
    (fp_line (start 0.599 0) (end 0.201 0)
      (stroke (width 0.15) (type solid)) (layer "F.Fab"))
    (fp_rect (start 0.848 0.4) (end -0.85 -0.402)
      (stroke (width 0.15) (type solid)) (fill none) (layer "F.Fab"))
    (pad "1" smd roundrect (at -0.7 0 270) (size 0.8 1) (layers "F.Cu" "F.Paste" "F.Mask") (roundrect_rratio 0.2)
      (net 309 "Net-(D3-C)") (pinfunction "C") (pintype "passive"))
    (pad "2" smd roundrect (at 0.7 0 270) (size 0.8 1) (layers "F.Cu" "F.Paste" "F.Mask") (roundrect_rratio 0.2)
      (net 310 "Net-(D3-A)") (pinfunction "A") (pintype "passive"))
  )
)
